(kicad_pcb
	(version 20260206)
	(generator "pcbnew")
	(generator_version "10.0")
	(general
		(thickness 1.6)
		(legacy_teardrops no)
	)
	(paper "A4")
	(title_block
		(title "9052_F0T_PDB_Converter_Brick_F_V03_1208_1600_OCP.brd")
		(comment 1 "Grand Teton / footprints 456-462 of 578")
	)
	(layers
		(0 "F.Cu" signal "TOP")
		(4 "In1.Cu" signal "GND")
		(6 "In2.Cu" signal "IN1")
		(8 "In3.Cu" signal "GND1")
		(10 "In4.Cu" signal "VCC")
		(12 "In5.Cu" signal "VCC1")
		(14 "In6.Cu" signal "GND2")
		(16 "In7.Cu" signal "IN2")
		(18 "In8.Cu" signal "GND3")
		(2 "B.Cu" signal "BOTTOM")
		(9 "F.Adhes" user "F.Adhesive")
		(11 "B.Adhes" user "B.Adhesive")
		(13 "F.Paste" user "Package Geometry/Pastemask Top")
		(15 "B.Paste" user "Package Geometry/Pastemask Bottom")
		(5 "F.SilkS" user "Ref Des/Silkscreen Top")
		(7 "B.SilkS" user "Ref Des/Silkscreen Bottom")
		(1 "F.Mask" user "Board Geometry/Soldermask Top")
		(3 "B.Mask" user "Board Geometry/Soldermask Bottom")
		(17 "Dwgs.User" user "User.Drawings")
		(19 "Cmts.User" user "User.Comments")
		(21 "Eco1.User" user "User.Eco1")
		(23 "Eco2.User" user "User.Eco2")
		(25 "Edge.Cuts" user "Board Geometry/Outline")
		(27 "Margin" user)
		(31 "F.CrtYd" user "Package Geometry/Place Bound Top")
		(29 "B.CrtYd" user "Package Geometry/Place Bound Bottom")
		(35 "F.Fab" user "Ref Des/Assembly Top")
		(33 "B.Fab" user "Ref Des/Assembly Bottom")
	)
	(footprint ""
		(layer "B.Cu")
		(at 237.031784 -88.74379 90)
		(property "Reference" "R3"
			(at 0 0 90)
			(layer "B.SilkS")
			(hide yes)
			(effects
				(font
					(size 1.27 1.27)
				)
				(justify mirror)
			)
		)
		(property "Value" ""
			(at 0 0 90)
			(layer "B.Fab")
			(effects
				(font
					(size 1.27 1.27)
				)
				(justify mirror)
			)
		)
		(duplicate_pad_numbers_are_jumpers no)
		(fp_line
			(start 0.7874 -0.4064)
			(end -0.7874 -0.4064)
			(stroke
				(width 0.1524)
				(type default)
			)
			(layer "B.SilkS")
		)
		(fp_line
			(start -0.7874 -0.4064)
			(end -0.7874 0.4064)
			(stroke
				(width 0.1524)
				(type default)
			)
			(layer "B.SilkS")
		)
		(fp_line
			(start 0.7874 0.4064)
			(end 0.7874 -0.4064)
			(stroke
				(width 0.1524)
				(type default)
			)
			(layer "B.SilkS")
		)
		(fp_line
			(start -0.7874 0.4064)
			(end 0.7874 0.4064)
			(stroke
				(width 0.1524)
				(type default)
			)
			(layer "B.SilkS")
		)
		(fp_line
			(start 0.67945 -0.305054)
			(end 0.12065 -0.305054)
			(stroke
				(width 0.1)
				(type default)
			)
			(layer "B.Fab")
		)
		(fp_line
			(start 0.12065 -0.305054)
			(end 0.12065 -0.2794)
			(stroke
				(width 0.1)
				(type default)
			)
			(layer "B.Fab")
		)
		(fp_line
			(start -0.12065 -0.3048)
			(end -0.67945 -0.3048)
			(stroke
				(width 0.1)
				(type default)
			)
			(layer "B.Fab")
		)
		(fp_line
			(start -0.67945 -0.3048)
			(end -0.67945 0.3048)
			(stroke
				(width 0.1)
				(type default)
			)
			(layer "B.Fab")
		)
		(fp_line
			(start 0.12065 -0.2794)
			(end -0.12065 -0.2794)
			(stroke
				(width 0.1)
				(type default)
			)
			(layer "B.Fab")
		)
		(fp_line
			(start -0.12065 -0.2794)
			(end -0.12065 -0.3048)
			(stroke
				(width 0.1)
				(type default)
			)
			(layer "B.Fab")
		)
		(fp_line
			(start 0.12065 0.2794)
			(end 0.12065 0.3048)
			(stroke
				(width 0.1)
				(type default)
			)
			(layer "B.Fab")
		)
		(fp_line
			(start -0.120396 0.2794)
			(end 0.12065 0.2794)
			(stroke
				(width 0.1)
				(type default)
			)
			(layer "B.Fab")
		)
		(fp_line
			(start 0.67945 0.3048)
			(end 0.67945 -0.305054)
			(stroke
				(width 0.1)
				(type default)
			)
			(layer "B.Fab")
		)
		(fp_line
			(start 0.12065 0.3048)
			(end 0.67945 0.3048)
			(stroke
				(width 0.1)
				(type default)
			)
			(layer "B.Fab")
		)
		(fp_line
			(start -0.120396 0.3048)
			(end -0.120396 0.2794)
			(stroke
				(width 0.1)
				(type default)
			)
			(layer "B.Fab")
		)
		(fp_line
			(start -0.67945 0.3048)
			(end -0.120396 0.3048)
			(stroke
				(width 0.1)
				(type default)
			)
			(layer "B.Fab")
		)
		(pad "1" smd circle
			(at 0.40005 0 270)
			(size 0 0)
			(layers "B.Cu" "B.Mask" "B.Paste")
			(net "PWRGD_P3V3_AUX_MB_BUF")
		)
		(pad "2" smd circle
			(at -0.40005 0 270)
			(size 0 0)
			(layers "B.Cu" "B.Mask" "B.Paste")
			(net "MB_MISC_I2C_EN")
		)
	)
	(footprint ""
		(layer "B.Cu")
		(at 215.519 -87.63 -90)
		(property "Reference" "U8"
			(at 3.46837 -0.2032 0)
			(unlocked yes)
			(layer "B.SilkS")
			(effects
				(font
					(size 0.7874 0.5842)
					(thickness 0.1524)
				)
				(justify left mirror)
			)
		)
		(property "Value" ""
			(at 0 0 90)
			(layer "B.Fab")
			(effects
				(font
					(size 1.27 1.27)
				)
				(justify mirror)
			)
		)
		(duplicate_pad_numbers_are_jumpers no)
		(fp_line
			(start -2.032 1.549908)
			(end 2.032 1.549908)
			(stroke
				(width 0.1524)
				(type default)
			)
			(layer "B.SilkS")
		)
		(fp_line
			(start 2.032 1.549908)
			(end 2.032 -1.549908)
			(stroke
				(width 0.1524)
				(type default)
			)
			(layer "B.SilkS")
		)
		(fp_line
			(start -2.032 -1.549908)
			(end -2.032 1.549908)
			(stroke
				(width 0.1524)
				(type default)
			)
			(layer "B.SilkS")
		)
		(fp_line
			(start 2.032 -1.549908)
			(end -2.032 -1.549908)
			(stroke
				(width 0.1524)
				(type default)
			)
			(layer "B.SilkS")
		)
		(fp_poly
			(pts
				(xy 1.397 -2.5654) (xy 1.905 -2.5654) (xy 1.651 -1.8034)
			)
			(stroke
				(width 0)
				(type default)
			)
			(fill yes)
			(layer "B.SilkS")
		)
		(fp_line
			(start -0.849884 1.549908)
			(end -0.849884 -1.549908)
			(stroke
				(width 0.1)
				(type default)
			)
			(layer "B.Fab")
		)
		(fp_line
			(start 0.849884 1.549908)
			(end -0.849884 1.549908)
			(stroke
				(width 0.1)
				(type default)
			)
			(layer "B.Fab")
		)
		(fp_line
			(start -0.849884 -1.549908)
			(end 0.849884 -1.549908)
			(stroke
				(width 0.1)
				(type default)
			)
			(layer "B.Fab")
		)
		(fp_line
			(start 0.849884 -1.549908)
			(end 0.849884 1.549908)
			(stroke
				(width 0.1)
				(type default)
			)
			(layer "B.Fab")
		)
		(fp_poly
			(pts
				(xy 2.9464 -1.2192) (xy 2.9464 -0.7112) (xy 2.1844 -0.9652)
			)
			(stroke
				(width 0)
				(type default)
			)
			(fill yes)
			(layer "B.Fab")
		)
		(pad "1" smd rect
			(at 1.225042 -0.94996 180)
			(size 0.4572 1.3208)
			(layers "B.Cu" "B.Mask" "B.Paste")
			(net "PWRGD_P3V3_AUX_MB_BUF_N")
		)
		(pad "2" smd rect
			(at 1.225042 0 180)
			(size 0.4572 1.3208)
			(layers "B.Cu" "B.Mask" "B.Paste")
			(net "FAN_PWR_EN")
		)
		(pad "3" smd rect
			(at 1.225042 0.94996 180)
			(size 0.4572 1.3208)
			(layers "B.Cu" "B.Mask" "B.Paste")
			(net "GND")
		)
		(pad "4" smd rect
			(at -1.225042 0.94996 180)
			(size 0.4572 1.3208)
			(layers "B.Cu" "B.Mask" "B.Paste")
			(net "FAN_PWR_EN_BUF_R")
		)
		(pad "5" smd rect
			(at -1.225042 -0.94996 180)
			(size 0.4572 1.3208)
			(layers "B.Cu" "B.Mask" "B.Paste")
			(net "P3V3_AUX")
		)
	)
	(footprint ""
		(layer "B.Cu")
		(at 100.849938 -76.708 90)
		(property "Reference" "PR73"
			(at 0 0 90)
			(layer "B.SilkS")
			(hide yes)
			(effects
				(font
					(size 1.27 1.27)
				)
				(justify mirror)
			)
		)
		(property "Value" ""
			(at 0 0 90)
			(layer "B.Fab")
			(effects
				(font
					(size 1.27 1.27)
				)
				(justify mirror)
			)
		)
		(duplicate_pad_numbers_are_jumpers no)
		(fp_line
			(start 0.7874 -0.4064)
			(end -0.7874 -0.4064)
			(stroke
				(width 0.1524)
				(type default)
			)
			(layer "B.SilkS")
		)
		(fp_line
			(start -0.7874 -0.4064)
			(end -0.7874 0.4064)
			(stroke
				(width 0.1524)
				(type default)
			)
			(layer "B.SilkS")
		)
		(fp_line
			(start 0.7874 0.4064)
			(end 0.7874 -0.4064)
			(stroke
				(width 0.1524)
				(type default)
			)
			(layer "B.SilkS")
		)
		(fp_line
			(start -0.7874 0.4064)
			(end 0.7874 0.4064)
			(stroke
				(width 0.1524)
				(type default)
			)
			(layer "B.SilkS")
		)
		(fp_line
			(start 0.67945 -0.305054)
			(end 0.12065 -0.305054)
			(stroke
				(width 0.1)
				(type default)
			)
			(layer "B.Fab")
		)
		(fp_line
			(start 0.12065 -0.305054)
			(end 0.12065 -0.2794)
			(stroke
				(width 0.1)
				(type default)
			)
			(layer "B.Fab")
		)
		(fp_line
			(start -0.12065 -0.3048)
			(end -0.67945 -0.3048)
			(stroke
				(width 0.1)
				(type default)
			)
			(layer "B.Fab")
		)
		(fp_line
			(start -0.67945 -0.3048)
			(end -0.67945 0.3048)
			(stroke
				(width 0.1)
				(type default)
			)
			(layer "B.Fab")
		)
		(fp_line
			(start 0.12065 -0.2794)
			(end -0.12065 -0.2794)
			(stroke
				(width 0.1)
				(type default)
			)
			(layer "B.Fab")
		)
		(fp_line
			(start -0.12065 -0.2794)
			(end -0.12065 -0.3048)
			(stroke
				(width 0.1)
				(type default)
			)
			(layer "B.Fab")
		)
		(fp_line
			(start 0.12065 0.2794)
			(end 0.12065 0.3048)
			(stroke
				(width 0.1)
				(type default)
			)
			(layer "B.Fab")
		)
		(fp_line
			(start -0.120396 0.2794)
			(end 0.12065 0.2794)
			(stroke
				(width 0.1)
				(type default)
			)
			(layer "B.Fab")
		)
		(fp_line
			(start 0.67945 0.3048)
			(end 0.67945 -0.305054)
			(stroke
				(width 0.1)
				(type default)
			)
			(layer "B.Fab")
		)
		(fp_line
			(start 0.12065 0.3048)
			(end 0.67945 0.3048)
			(stroke
				(width 0.1)
				(type default)
			)
			(layer "B.Fab")
		)
		(fp_line
			(start -0.120396 0.3048)
			(end -0.120396 0.2794)
			(stroke
				(width 0.1)
				(type default)
			)
			(layer "B.Fab")
		)
		(fp_line
			(start -0.67945 0.3048)
			(end -0.120396 0.3048)
			(stroke
				(width 0.1)
				(type default)
			)
			(layer "B.Fab")
		)
		(pad "1" smd circle
			(at 0.40005 0 270)
			(size 0 0)
			(layers "B.Cu" "B.Mask" "B.Paste")
			(net "GND")
		)
		(pad "2" smd circle
			(at -0.40005 0 270)
			(size 0 0)
			(layers "B.Cu" "B.Mask" "B.Paste")
			(net "BRICK1_PMBADD")
		)
	)
	(footprint ""
		(layer "B.Cu")
		(at 222.377 -95.504 90)
		(property "Reference" "C38"
			(at 0 0 90)
			(layer "B.SilkS")
			(hide yes)
			(effects
				(font
					(size 1.27 1.27)
				)
				(justify mirror)
			)
		)
		(property "Value" ""
			(at 0 0 90)
			(layer "B.Fab")
			(effects
				(font
					(size 1.27 1.27)
				)
				(justify mirror)
			)
		)
		(duplicate_pad_numbers_are_jumpers no)
		(fp_line
			(start 2.2098 -0.9398)
			(end -2.2098 -0.9398)
			(stroke
				(width 0.1524)
				(type default)
			)
			(layer "B.SilkS")
		)
		(fp_line
			(start -2.2098 -0.9398)
			(end -2.2098 0.9398)
			(stroke
				(width 0.1524)
				(type default)
			)
			(layer "B.SilkS")
		)
		(fp_line
			(start 2.2098 0.9398)
			(end 2.2098 -0.9398)
			(stroke
				(width 0.1524)
				(type default)
			)
			(layer "B.SilkS")
		)
		(fp_line
			(start -2.2098 0.9398)
			(end 2.2098 0.9398)
			(stroke
				(width 0.1524)
				(type default)
			)
			(layer "B.SilkS")
		)
		(fp_line
			(start 1.700022 -0.899922)
			(end -1.700022 -0.899922)
			(stroke
				(width 0.1)
				(type default)
			)
			(layer "B.Fab")
		)
		(fp_line
			(start -1.700022 -0.899922)
			(end -1.700022 0.899922)
			(stroke
				(width 0.1)
				(type default)
			)
			(layer "B.Fab")
		)
		(fp_line
			(start 1.700022 0.899922)
			(end 1.700022 -0.899922)
			(stroke
				(width 0.1)
				(type default)
			)
			(layer "B.Fab")
		)
		(fp_line
			(start -1.700022 0.899922)
			(end 1.700022 0.899922)
			(stroke
				(width 0.1)
				(type default)
			)
			(layer "B.Fab")
		)
		(pad "1" smd rect
			(at 1.4732 0 90)
			(size 1.1684 1.5748)
			(layers "B.Cu" "B.Mask" "B.Paste")
			(net "P52V_HS")
		)
		(pad "2" smd rect
			(at -1.4732 0 90)
			(size 1.1684 1.5748)
			(layers "B.Cu" "B.Mask" "B.Paste")
			(net "GND")
		)
	)
	(footprint ""
		(layer "B.Cu")
		(at 274.026122 -91.298522 180)
		(property "Reference" "R5863"
			(at 0 0 0)
			(layer "B.SilkS")
			(hide yes)
			(effects
				(font
					(size 1.27 1.27)
				)
				(justify mirror)
			)
		)
		(property "Value" ""
			(at 0 0 0)
			(layer "B.Fab")
			(effects
				(font
					(size 1.27 1.27)
				)
				(justify mirror)
			)
		)
		(duplicate_pad_numbers_are_jumpers no)
		(fp_line
			(start 0.7874 0.4064)
			(end 0.7874 -0.4064)
			(stroke
				(width 0.1524)
				(type default)
			)
			(layer "B.SilkS")
		)
		(fp_line
			(start 0.7874 -0.4064)
			(end -0.7874 -0.4064)
			(stroke
				(width 0.1524)
				(type default)
			)
			(layer "B.SilkS")
		)
		(fp_line
			(start -0.7874 0.4064)
			(end 0.7874 0.4064)
			(stroke
				(width 0.1524)
				(type default)
			)
			(layer "B.SilkS")
		)
		(fp_line
			(start -0.7874 -0.4064)
			(end -0.7874 0.4064)
			(stroke
				(width 0.1524)
				(type default)
			)
			(layer "B.SilkS")
		)
		(fp_line
			(start 0.67945 0.3048)
			(end 0.67945 -0.305054)
			(stroke
				(width 0.1)
				(type default)
			)
			(layer "B.Fab")
		)
		(fp_line
			(start 0.67945 -0.305054)
			(end 0.12065 -0.305054)
			(stroke
				(width 0.1)
				(type default)
			)
			(layer "B.Fab")
		)
		(fp_line
			(start 0.12065 0.3048)
			(end 0.67945 0.3048)
			(stroke
				(width 0.1)
				(type default)
			)
			(layer "B.Fab")
		)
		(fp_line
			(start 0.12065 0.2794)
			(end 0.12065 0.3048)
			(stroke
				(width 0.1)
				(type default)
			)
			(layer "B.Fab")
		)
		(fp_line
			(start 0.12065 -0.2794)
			(end -0.12065 -0.2794)
			(stroke
				(width 0.1)
				(type default)
			)
			(layer "B.Fab")
		)
		(fp_line
			(start 0.12065 -0.305054)
			(end 0.12065 -0.2794)
			(stroke
				(width 0.1)
				(type default)
			)
			(layer "B.Fab")
		)
		(fp_line
			(start -0.120396 0.3048)
			(end -0.120396 0.2794)
			(stroke
				(width 0.1)
				(type default)
			)
			(layer "B.Fab")
		)
		(fp_line
			(start -0.120396 0.2794)
			(end 0.12065 0.2794)
			(stroke
				(width 0.1)
				(type default)
			)
			(layer "B.Fab")
		)
		(fp_line
			(start -0.12065 -0.2794)
			(end -0.12065 -0.3048)
			(stroke
				(width 0.1)
				(type default)
			)
			(layer "B.Fab")
		)
		(fp_line
			(start -0.12065 -0.3048)
			(end -0.67945 -0.3048)
			(stroke
				(width 0.1)
				(type default)
			)
			(layer "B.Fab")
		)
		(fp_line
			(start -0.67945 0.3048)
			(end -0.120396 0.3048)
			(stroke
				(width 0.1)
				(type default)
			)
			(layer "B.Fab")
		)
		(fp_line
			(start -0.67945 -0.3048)
			(end -0.67945 0.3048)
			(stroke
				(width 0.1)
				(type default)
			)
			(layer "B.Fab")
		)
		(pad "1" smd circle
			(at 0.40005 0)
			(size 0 0)
			(layers "B.Cu" "B.Mask" "B.Paste")
			(net "P52V_HS1_GATE2_R")
		)
		(pad "2" smd circle
			(at -0.40005 0)
			(size 0 0)
			(layers "B.Cu" "B.Mask" "B.Paste")
			(net "P52V_HS1_4287_GATE2_R")
		)
	)
	(footprint ""
		(layer "B.Cu")
		(at 242.4557 -19.6215)
		(property "Reference" ""
			(at 0 0 0)
			(layer "B.SilkS")
			(hide yes)
			(effects
				(font
					(size 1.27 1.27)
				)
				(justify mirror)
			)
		)
		(property "Value" ""
			(at 0 0 0)
			(layer "B.Fab")
			(effects
				(font
					(size 1.27 1.27)
				)
				(justify mirror)
			)
		)
		(duplicate_pad_numbers_are_jumpers no)
		(pad "1" smd circle
			(at 0 0 180)
			(size 0.9906 0.9906)
			(layers "B.Cu" "B.Mask" "B.Paste")
			(net "Net_152")
		)
		(zone
			(layer "B.Cu")
			(hatch none 0.5)
			(connect_pads
				(clearance 0)
			)
			(min_thickness 0.25)
			(keepout
				(tracks not_allowed)
				(vias allowed)
				(pads allowed)
				(copperpour not_allowed)
				(footprints allowed)
			)
			(placement
				(enabled no)
				(sheetname "")
			)
			(fill
				(thermal_gap 0.5)
				(thermal_bridge_width 0.5)
				(island_removal_mode 0)
			)
			(polygon
				(pts
					(arc
						(start 244.0813 -19.6215)
						(mid 240.8301 -19.6215)
						(end 244.0813 -19.6215)
					)
				)
			)
		)
	)
	(footprint ""
		(layer "B.Cu")
		(at 222.25 -78.359 -90)
		(property "Reference" "R39"
			(at 0 0 90)
			(layer "B.SilkS")
			(hide yes)
			(effects
				(font
					(size 1.27 1.27)
				)
				(justify mirror)
			)
		)
		(property "Value" ""
			(at 0 0 90)
			(layer "B.Fab")
			(effects
				(font
					(size 1.27 1.27)
				)
				(justify mirror)
			)
		)
		(duplicate_pad_numbers_are_jumpers no)
		(fp_line
			(start -0.7874 0.4064)
			(end 0.7874 0.4064)
			(stroke
				(width 0.1524)
				(type default)
			)
			(layer "B.SilkS")
		)
		(fp_line
			(start 0.7874 0.4064)
			(end 0.7874 -0.4064)
			(stroke
				(width 0.1524)
				(type default)
			)
			(layer "B.SilkS")
		)
		(fp_line
			(start -0.7874 -0.4064)
			(end -0.7874 0.4064)
			(stroke
				(width 0.1524)
				(type default)
			)
			(layer "B.SilkS")
		)
		(fp_line
			(start 0.7874 -0.4064)
			(end -0.7874 -0.4064)
			(stroke
				(width 0.1524)
				(type default)
			)
			(layer "B.SilkS")
		)
		(fp_line
			(start -0.67945 0.3048)
			(end -0.120396 0.3048)
			(stroke
				(width 0.1)
				(type default)
			)
			(layer "B.Fab")
		)
		(fp_line
			(start -0.120396 0.3048)
			(end -0.120396 0.2794)
			(stroke
				(width 0.1)
				(type default)
			)
			(layer "B.Fab")
		)
		(fp_line
			(start 0.12065 0.3048)
			(end 0.67945 0.3048)
			(stroke
				(width 0.1)
				(type default)
			)
			(layer "B.Fab")
		)
		(fp_line
			(start 0.67945 0.3048)
			(end 0.67945 -0.305054)
			(stroke
				(width 0.1)
				(type default)
			)
			(layer "B.Fab")
		)
		(fp_line
			(start -0.120396 0.2794)
			(end 0.12065 0.2794)
			(stroke
				(width 0.1)
				(type default)
			)
			(layer "B.Fab")
		)
		(fp_line
			(start 0.12065 0.2794)
			(end 0.12065 0.3048)
			(stroke
				(width 0.1)
				(type default)
			)
			(layer "B.Fab")
		)
		(fp_line
			(start -0.12065 -0.2794)
			(end -0.12065 -0.3048)
			(stroke
				(width 0.1)
				(type default)
			)
			(layer "B.Fab")
		)
		(fp_line
			(start 0.12065 -0.2794)
			(end -0.12065 -0.2794)
			(stroke
				(width 0.1)
				(type default)
			)
			(layer "B.Fab")
		)
		(fp_line
			(start -0.67945 -0.3048)
			(end -0.67945 0.3048)
			(stroke
				(width 0.1)
				(type default)
			)
			(layer "B.Fab")
		)
		(fp_line
			(start -0.12065 -0.3048)
			(end -0.67945 -0.3048)
			(stroke
				(width 0.1)
				(type default)
			)
			(layer "B.Fab")
		)
		(fp_line
			(start 0.12065 -0.305054)
			(end 0.12065 -0.2794)
			(stroke
				(width 0.1)
				(type default)
			)
			(layer "B.Fab")
		)
		(fp_line
			(start 0.67945 -0.305054)
			(end 0.12065 -0.305054)
			(stroke
				(width 0.1)
				(type default)
			)
			(layer "B.Fab")
		)
		(pad "1" smd circle
			(at 0.40005 0 90)
			(size 0 0)
			(layers "B.Cu" "B.Mask" "B.Paste")
			(net "P3V3_AUX")
		)
		(pad "2" smd circle
			(at -0.40005 0 90)
			(size 0 0)
			(layers "B.Cu" "B.Mask" "B.Paste")
			(net "FRU_ADDR1")
		)
	)
)
